(kicad_pcb
	(version 20241229)
	(generator "pcbnew")
	(generator_version "9.0")
	(general
		(thickness 1.62)
		(legacy_teardrops no)
	)
	(paper "A4")
	(title_block
		(title "OCuLink to 10GbE adapter")
		(date "2026-02-23")
		(rev "1.1.0")
		(company "Antmicro Ltd")
		(comment 1 "www.antmicro.com")
		(comment 9 "footprints 500-504 of 510")
	)
	(layers
		(0 "F.Cu" signal)
		(4 "In1.Cu" signal)
		(6 "In2.Cu" signal)
		(8 "In3.Cu" signal)
		(10 "In4.Cu" signal)
		(12 "In5.Cu" signal)
		(14 "In6.Cu" signal)
		(2 "B.Cu" signal)
		(9 "F.Adhes" user "F.Adhesive")
		(11 "B.Adhes" user "B.Adhesive")
		(13 "F.Paste" user)
		(15 "B.Paste" user)
		(5 "F.SilkS" user "F.Silkscreen")
		(7 "B.SilkS" user "B.Silkscreen")
		(1 "F.Mask" user)
		(3 "B.Mask" user)
		(17 "Dwgs.User" user "User.Drawings")
		(19 "Cmts.User" user "User.Comments")
		(21 "Eco1.User" user "User.Eco1")
		(23 "Eco2.User" user "User.Eco2")
		(25 "Edge.Cuts" user)
		(27 "Margin" user)
		(31 "F.CrtYd" user "F.Courtyard")
		(29 "B.CrtYd" user "B.Courtyard")
		(35 "F.Fab" user)
		(33 "B.Fab" user)
	)
	(footprint "antmicro-footprints:SOT-416"
		(layer "B.Cu")
		(at 56.25 120.4)
		(descr "SOT-416")
		(tags "SOT-416")
		(property "Reference" "Q8"
			(at 1.169999 0.8 90)
			(layer "B.SilkS")
			(effects
				(font
					(size 0.7 0.7)
					(thickness 0.15)
				)
				(justify right top mirror)
			)
		)
		(property "Value" "DTC014T_SOT-416"
			(at 0 -2.000001 0)
			(layer "B.Fab")
			(hide yes)
			(effects
				(font
					(size 0.7 0.7)
					(thickness 0.15)
				)
				(justify right top mirror)
			)
		)
		(property "Datasheet" "https://www.rohm.com/datasheet?p=DTC014TEB&dist=Mouser&media=referral&source=mouser.com&campaign=Mouser"
			(at 0 0 0)
			(layer "B.Fab")
			(hide yes)
			(effects
				(font
					(size 1.27 1.27)
					(thickness 0.15)
				)
				(justify mirror)
			)
		)
		(property "Description" "Bipolar (BJT) Single Transistor with built-in base resistor, NPN, 50V, 100mA, 150mW, SOT-416FL, Surface Mount"
			(at 0 0 0)
			(layer "B.Fab")
			(hide yes)
			(effects
				(font
					(size 1.27 1.27)
					(thickness 0.15)
				)
				(justify mirror)
			)
		)
		(property "Manufacturer" "ROHM Semiconductor"
			(at 0 0 180)
			(unlocked yes)
			(layer "B.Fab")
			(hide yes)
			(effects
				(font
					(size 1 1)
					(thickness 0.15)
				)
				(justify mirror)
			)
		)
		(property "MPN" "DTC014TEBTL"
			(at 0 0 180)
			(unlocked yes)
			(layer "B.Fab")
			(hide yes)
			(effects
				(font
					(size 1 1)
					(thickness 0.15)
				)
				(justify mirror)
			)
		)
		(property "Author" "Antmicro"
			(at 0 0 180)
			(unlocked yes)
			(layer "B.Fab")
			(hide yes)
			(effects
				(font
					(size 1 1)
					(thickness 0.15)
				)
				(justify mirror)
			)
		)
		(property "License" "Apache-2.0"
			(at 0 0 180)
			(unlocked yes)
			(layer "B.Fab")
			(hide yes)
			(effects
				(font
					(size 1 1)
					(thickness 0.15)
				)
				(justify mirror)
			)
		)
		(sheetname "/Power/")
		(sheetfile "power.kicad_sch")
		(attr smd)
		(fp_line
			(start -0.5 0.15)
			(end -0.5 -0.15)
			(stroke
				(width 0.15)
				(type solid)
			)
			(layer "B.SilkS")
		)
		(fp_line
			(start 0.5 -0.9)
			(end -0.5 -0.9)
			(stroke
				(width 0.15)
				(type solid)
			)
			(layer "B.SilkS")
		)
		(fp_line
			(start 0.5 -0.9)
			(end 0.5 -0.7)
			(stroke
				(width 0.15)
				(type solid)
			)
			(layer "B.SilkS")
		)
		(fp_line
			(start 0.508 0.9)
			(end -0.5 0.9)
			(stroke
				(width 0.15)
				(type solid)
			)
			(layer "B.SilkS")
		)
		(fp_line
			(start 0.508 0.9)
			(end 0.508 0.592)
			(stroke
				(width 0.15)
				(type solid)
			)
			(layer "B.SilkS")
		)
		(fp_rect
			(start -1 1.05)
			(end 1 -1.05)
			(stroke
				(width 0.05)
				(type solid)
			)
			(fill no)
			(layer "B.CrtYd")
		)
		(fp_line
			(start -0.05 0.9)
			(end -0.45 0.5)
			(stroke
				(width 0.15)
				(type solid)
			)
			(layer "B.Fab")
		)
		(fp_rect
			(start 0.45 -0.9)
			(end -0.45 0.9)
			(stroke
				(width 0.15)
				(type solid)
			)
			(fill no)
			(layer "B.Fab")
		)
		(fp_text user "License: Apache-2.0"
			(at -1 -5.802 180)
			(layer "B.Fab")
			(effects
				(font
					(size 0.7 0.7)
					(thickness 0.15)
				)
				(justify left bottom mirror)
			)
		)
		(fp_text user "Author: Antmicro"
			(at -1 -4.602 180)
			(layer "B.Fab")
			(effects
				(font
					(size 0.7 0.7)
					(thickness 0.15)
				)
				(justify left bottom mirror)
			)
		)
		(fp_text user "${REFERENCE}"
			(at -1 -3.4 180)
			(layer "B.Fab")
			(effects
				(font
					(size 0.7 0.7)
					(thickness 0.15)
				)
				(justify left bottom mirror)
			)
		)
		(pad "1" smd rect
			(at -0.652 0.5)
			(size 0.6 0.5)
			(layers "B.Cu" "B.Mask" "B.Paste")
			(net 312 "/Power/+1V0_OUT")
			(pinfunction "B")
			(pintype "input")
		)
		(pad "2" smd rect
			(at -0.652 -0.498)
			(size 0.6 0.5)
			(layers "B.Cu" "B.Mask" "B.Paste")
			(net 28 "GND")
			(pinfunction "E")
			(pintype "passive")
		)
		(pad "3" smd rect
			(at 0.65 0)
			(size 0.6 0.5)
			(layers "B.Cu" "B.Mask" "B.Paste")
			(net 418 "Net-(Q8-C)")
			(pinfunction "C")
			(pintype "passive")
		)
	)
	(footprint "antmicro-footprints:R_0402_1005Metric"
		(layer "B.Cu")
		(at 83.225 94.6 90)
		(descr "Resistor SMD 0402")
		(tags "resistor SMD 0402")
		(property "Reference" "R134"
			(at 12.5 -0.462343 90)
			(layer "B.SilkS")
			(effects
				(font
					(size 0.7 0.7)
					(thickness 0.15)
				)
				(justify right top mirror)
			)
		)
		(property "Value" "R_100R_0402"
			(at -1.011843 -1.772046 90)
			(layer "B.Fab")
			(hide yes)
			(effects
				(font
					(size 0.7 0.7)
					(thickness 0.15)
				)
				(justify right top mirror)
			)
		)
		(property "Datasheet" "https://www.bourns.com/docs/product-datasheets/cr.pdf"
			(at 0 0 90)
			(layer "B.Fab")
			(hide yes)
			(effects
				(font
					(size 1.27 1.27)
					(thickness 0.15)
				)
				(justify mirror)
			)
		)
		(property "Description" "SMD Chip Resistor, 100 ohm, ± 1%, 62.5 mW, 0402 [1005 Metric], Thick Film, General Purpose"
			(at 0 0 90)
			(layer "B.Fab")
			(hide yes)
			(effects
				(font
					(size 1.27 1.27)
					(thickness 0.15)
				)
				(justify mirror)
			)
		)
		(property "MPN" "CR0402-FX-1000GLF"
			(at 0 0 90)
			(unlocked yes)
			(layer "B.Fab")
			(hide yes)
			(effects
				(font
					(size 1 1)
					(thickness 0.15)
				)
				(justify mirror)
			)
		)
		(property "Manufacturer" "Bourns"
			(at 0 0 90)
			(unlocked yes)
			(layer "B.Fab")
			(hide yes)
			(effects
				(font
					(size 1 1)
					(thickness 0.15)
				)
				(justify mirror)
			)
		)
		(property "License" "Apache-2.0"
			(at 0 0 90)
			(unlocked yes)
			(layer "B.Fab")
			(hide yes)
			(effects
				(font
					(size 1 1)
					(thickness 0.15)
				)
				(justify mirror)
			)
		)
		(property "Author" "Antmicro"
			(at 0 0 90)
			(unlocked yes)
			(layer "B.Fab")
			(hide yes)
			(effects
				(font
					(size 1 1)
					(thickness 0.15)
				)
				(justify mirror)
			)
		)
		(property "Val" "100R"
			(at 0 0 90)
			(unlocked yes)
			(layer "B.Fab")
			(hide yes)
			(effects
				(font
					(size 1 1)
					(thickness 0.15)
				)
				(justify mirror)
			)
		)
		(property "Tolerance" "1%"
			(at 0 0 90)
			(unlocked yes)
			(layer "B.Fab")
			(hide yes)
			(effects
				(font
					(size 1 1)
					(thickness 0.15)
				)
				(justify mirror)
			)
		)
		(sheetname "/X710-AT2 RSVD/")
		(sheetfile "x710-at2-rsvd.kicad_sch")
		(attr smd)
		(fp_rect
			(start -0.925 0.47)
			(end 0.925 -0.47)
			(stroke
				(width 0.05)
				(type default)
			)
			(fill no)
			(layer "B.CrtYd")
		)
		(fp_rect
			(start -0.5 0.25)
			(end 0.5 -0.25)
			(stroke
				(width 0.15)
				(type solid)
			)
			(fill no)
			(layer "B.Fab")
		)
		(pad "1" smd roundrect
			(at -0.48 0 90)
			(size 0.59 0.64)
			(layers "B.Cu" "B.Mask" "B.Paste")
			(roundrect_rratio 0.25)
			(net 28 "GND")
			(pintype "passive")
		)
		(pad "2" smd roundrect
			(at 0.48 0 90)
			(size 0.59 0.64)
			(layers "B.Cu" "B.Mask" "B.Paste")
			(roundrect_rratio 0.25)
			(net 122 "/X710-AT2 RSVD/RSVDY24_VSS")
			(pintype "passive")
		)
	)
	(footprint "antmicro-footprints:R_0402_1005Metric"
		(layer "B.Cu")
		(at 89.5 111.15 -90)
		(descr "Resistor SMD 0402")
		(tags "resistor SMD 0402")
		(property "Reference" "R142"
			(at 0.76 -0.319195 90)
			(layer "B.SilkS")
			(effects
				(font
					(size 0.7 0.7)
					(thickness 0.15)
				)
				(justify left bottom mirror)
			)
		)
		(property "Value" "R_1k_0402"
			(at -1.011843 -1.772046 90)
			(layer "B.Fab")
			(hide yes)
			(effects
				(font
					(size 0.7 0.7)
					(thickness 0.15)
				)
				(justify left bottom mirror)
			)
		)
		(property "Datasheet" "https://www.bourns.com/docs/product-datasheets/cr.pdf"
			(at 0 0 90)
			(layer "B.Fab")
			(hide yes)
			(effects
				(font
					(size 1.27 1.27)
					(thickness 0.15)
				)
				(justify mirror)
			)
		)
		(property "Description" "SMD Chip Resistor, 1 kohm, ± 1%, 63 mW, 0402 [1005 Metric], Thick Film, General Purpose"
			(at 0 0 90)
			(layer "B.Fab")
			(hide yes)
			(effects
				(font
					(size 1.27 1.27)
					(thickness 0.15)
				)
				(justify mirror)
			)
		)
		(property "MPN" "CR0402-FX-1001GLF"
			(at 0 0 270)
			(unlocked yes)
			(layer "B.Fab")
			(hide yes)
			(effects
				(font
					(size 1 1)
					(thickness 0.15)
				)
				(justify mirror)
			)
		)
		(property "Manufacturer" "Bourns"
			(at 0 0 270)
			(unlocked yes)
			(layer "B.Fab")
			(hide yes)
			(effects
				(font
					(size 1 1)
					(thickness 0.15)
				)
				(justify mirror)
			)
		)
		(property "License" "Apache-2.0"
			(at 0 0 270)
			(unlocked yes)
			(layer "B.Fab")
			(hide yes)
			(effects
				(font
					(size 1 1)
					(thickness 0.15)
				)
				(justify mirror)
			)
		)
		(property "Author" "Antmicro"
			(at 0 0 270)
			(unlocked yes)
			(layer "B.Fab")
			(hide yes)
			(effects
				(font
					(size 1 1)
					(thickness 0.15)
				)
				(justify mirror)
			)
		)
		(property "Val" "1k"
			(at 0 0 270)
			(unlocked yes)
			(layer "B.Fab")
			(hide yes)
			(effects
				(font
					(size 1 1)
					(thickness 0.15)
				)
				(justify mirror)
			)
		)
		(property "Tolerance" "1%"
			(at 0 0 270)
			(unlocked yes)
			(layer "B.Fab")
			(hide yes)
			(effects
				(font
					(size 1 1)
					(thickness 0.15)
				)
				(justify mirror)
			)
		)
		(sheetname "/X710-AT2 RSVD/")
		(sheetfile "x710-at2-rsvd.kicad_sch")
		(attr smd)
		(fp_rect
			(start -0.925 0.47)
			(end 0.925 -0.47)
			(stroke
				(width 0.05)
				(type default)
			)
			(fill no)
			(layer "B.CrtYd")
		)
		(fp_rect
			(start -0.5 0.25)
			(end 0.5 -0.25)
			(stroke
				(width 0.15)
				(type solid)
			)
			(fill no)
			(layer "B.Fab")
		)
		(pad "1" smd roundrect
			(at -0.48 0 270)
			(size 0.59 0.64)
			(layers "B.Cu" "B.Mask" "B.Paste")
			(roundrect_rratio 0.25)
			(net 131 "/X710-AT2 RSVD/RSVDD8_1P88V")
			(pintype "passive")
		)
		(pad "2" smd roundrect
			(at 0.48 0 270)
			(size 0.59 0.64)
			(layers "B.Cu" "B.Mask" "B.Paste")
			(roundrect_rratio 0.25)
			(net 18 "+1V88")
			(pintype "passive")
		)
	)
	(footprint "antmicro-footprints:R_0402_1005Metric"
		(layer "B.Cu")
		(at 91.2 100.15 90)
		(descr "Resistor SMD 0402")
		(tags "resistor SMD 0402")
		(property "Reference" "R137"
			(at 9.87 -0.352343 90)
			(layer "B.SilkS")
			(effects
				(font
					(size 0.7 0.7)
					(thickness 0.15)
				)
				(justify right top mirror)
			)
		)
		(property "Value" "R_100R_0402"
			(at -1.011843 -1.772046 90)
			(layer "B.Fab")
			(hide yes)
			(effects
				(font
					(size 0.7 0.7)
					(thickness 0.15)
				)
				(justify right top mirror)
			)
		)
		(property "Datasheet" "https://www.bourns.com/docs/product-datasheets/cr.pdf"
			(at 0 0 90)
			(layer "B.Fab")
			(hide yes)
			(effects
				(font
					(size 1.27 1.27)
					(thickness 0.15)
				)
				(justify mirror)
			)
		)
		(property "Description" "SMD Chip Resistor, 100 ohm, ± 1%, 62.5 mW, 0402 [1005 Metric], Thick Film, General Purpose"
			(at 0 0 90)
			(layer "B.Fab")
			(hide yes)
			(effects
				(font
					(size 1.27 1.27)
					(thickness 0.15)
				)
				(justify mirror)
			)
		)
		(property "MPN" "CR0402-FX-1000GLF"
			(at 0 0 90)
			(unlocked yes)
			(layer "B.Fab")
			(hide yes)
			(effects
				(font
					(size 1 1)
					(thickness 0.15)
				)
				(justify mirror)
			)
		)
		(property "Manufacturer" "Bourns"
			(at 0 0 90)
			(unlocked yes)
			(layer "B.Fab")
			(hide yes)
			(effects
				(font
					(size 1 1)
					(thickness 0.15)
				)
				(justify mirror)
			)
		)
		(property "License" "Apache-2.0"
			(at 0 0 90)
			(unlocked yes)
			(layer "B.Fab")
			(hide yes)
			(effects
				(font
					(size 1 1)
					(thickness 0.15)
				)
				(justify mirror)
			)
		)
		(property "Author" "Antmicro"
			(at 0 0 90)
			(unlocked yes)
			(layer "B.Fab")
			(hide yes)
			(effects
				(font
					(size 1 1)
					(thickness 0.15)
				)
				(justify mirror)
			)
		)
		(property "Val" "100R"
			(at 0 0 90)
			(unlocked yes)
			(layer "B.Fab")
			(hide yes)
			(effects
				(font
					(size 1 1)
					(thickness 0.15)
				)
				(justify mirror)
			)
		)
		(property "Tolerance" "1%"
			(at 0 0 90)
			(unlocked yes)
			(layer "B.Fab")
			(hide yes)
			(effects
				(font
					(size 1 1)
					(thickness 0.15)
				)
				(justify mirror)
			)
		)
		(sheetname "/X710-AT2 RSVD/")
		(sheetfile "x710-at2-rsvd.kicad_sch")
		(attr smd)
		(fp_rect
			(start -0.925 0.47)
			(end 0.925 -0.47)
			(stroke
				(width 0.05)
				(type default)
			)
			(fill no)
			(layer "B.CrtYd")
		)
		(fp_rect
			(start -0.5 0.25)
			(end 0.5 -0.25)
			(stroke
				(width 0.15)
				(type solid)
			)
			(fill no)
			(layer "B.Fab")
		)
		(pad "1" smd roundrect
			(at -0.48 0 90)
			(size 0.59 0.64)
			(layers "B.Cu" "B.Mask" "B.Paste")
			(roundrect_rratio 0.25)
			(net 28 "GND")
			(pintype "passive")
		)
		(pad "2" smd roundrect
			(at 0.48 0 90)
			(size 0.59 0.64)
			(layers "B.Cu" "B.Mask" "B.Paste")
			(roundrect_rratio 0.25)
			(net 125 "/X710-AT2 RSVD/RSVDN9_VSS")
			(pintype "passive")
		)
	)
	(footprint "antmicro-footprints:C_0402_1005Metric"
		(layer "B.Cu")
		(at 88.225 96.45 90)
		(descr "Capacitor SMD 0402")
		(tags "capacitor SMD 0402")
		(property "Reference" "C113"
			(at 11.58 -0.432343 90)
			(layer "B.SilkS")
			(effects
				(font
					(size 0.7 0.7)
					(thickness 0.15)
				)
				(justify right top mirror)
			)
		)
		(property "Value" "C_1u_25V_0402"
			(at -1.022927 -2.155213 90)
			(layer "B.Fab")
			(hide yes)
			(effects
				(font
					(size 0.7 0.7)
					(thickness 0.15)
				)
				(justify right top mirror)
			)
		)
		(property "Datasheet" "https://www.murata.com/products/productdetail?partno=GRM155R61E105KE11%23"
			(at 0 0 90)
			(layer "B.Fab")
			(hide yes)
			(effects
				(font
					(size 1.27 1.27)
					(thickness 0.15)
				)
				(justify mirror)
			)
		)
		(property "Description" "SMD Multilayer Ceramic Capacitor, 1 µF, 25 V, 0402 [1005 Metric], ± 10%, X5R, GRM Series"
			(at 0 0 90)
			(layer "B.Fab")
			(hide yes)
			(effects
				(font
					(size 1.27 1.27)
					(thickness 0.15)
				)
				(justify mirror)
			)
		)
		(property "MPN" "GRM155R61E105KE11J"
			(at 0 0 90)
			(unlocked yes)
			(layer "B.Fab")
			(hide yes)
			(effects
				(font
					(size 1 1)
					(thickness 0.15)
				)
				(justify mirror)
			)
		)
		(property "Manufacturer" "Murata"
			(at 0 0 90)
			(unlocked yes)
			(layer "B.Fab")
			(hide yes)
			(effects
				(font
					(size 1 1)
					(thickness 0.15)
				)
				(justify mirror)
			)
		)
		(property "License" "Apache-2.0"
			(at 0 0 90)
			(unlocked yes)
			(layer "B.Fab")
			(hide yes)
			(effects
				(font
					(size 1 1)
					(thickness 0.15)
				)
				(justify mirror)
			)
		)
		(property "Author" "Antmicro"
			(at 0 0 90)
			(unlocked yes)
			(layer "B.Fab")
			(hide yes)
			(effects
				(font
					(size 1 1)
					(thickness 0.15)
				)
				(justify mirror)
			)
		)
		(property "Val" "1u"
			(at 0 0 90)
			(unlocked yes)
			(layer "B.Fab")
			(hide yes)
			(effects
				(font
					(size 1 1)
					(thickness 0.15)
				)
				(justify mirror)
			)
		)
		(property "Voltage" "25V"
			(at 0 0 90)
			(unlocked yes)
			(layer "B.Fab")
			(hide yes)
			(effects
				(font
					(size 1 1)
					(thickness 0.15)
				)
				(justify mirror)
			)
		)
		(property "Dielectric" "X5R"
			(at 0 0 90)
			(unlocked yes)
			(layer "B.Fab")
			(hide yes)
			(effects
				(font
					(size 1 1)
					(thickness 0.15)
				)
				(justify mirror)
			)
		)
		(sheetname "/X710-AT2 power/")
		(sheetfile "x710-at2-power.kicad_sch")
		(attr smd)
		(fp_rect
			(start -0.925 0.47)
			(end 0.925 -0.47)
			(stroke
				(width 0.05)
				(type default)
			)
			(fill no)
			(layer "B.CrtYd")
		)
		(fp_line
			(start 0.504 -0.248)
			(end -0.494 -0.248)
			(stroke
				(width 0.15)
				(type solid)
			)
			(layer "B.Fab")
		)
		(fp_line
			(start -0.494 -0.248)
			(end -0.494 0.25)
			(stroke
				(width 0.15)
				(type solid)
			)
			(layer "B.Fab")
		)
		(fp_line
			(start 0.504 0.25)
			(end 0.504 -0.248)
			(stroke
				(width 0.15)
				(type solid)
			)
			(layer "B.Fab")
		)
		(fp_line
			(start -0.494 0.25)
			(end 0.504 0.25)
			(stroke
				(width 0.15)
				(type solid)
			)
			(layer "B.Fab")
		)
		(pad "1" smd roundrect
			(at -0.48 0 90)
			(size 0.59 0.64)
			(layers "B.Cu" "B.Mask" "B.Paste")
			(roundrect_rratio 0.25)
			(net 28 "GND")
			(pintype "passive")
		)
		(pad "2" smd roundrect
			(at 0.48 0 90)
			(size 0.59 0.64)
			(layers "B.Cu" "B.Mask" "B.Paste")
			(roundrect_rratio 0.25)
			(net 9 "VCCD")
			(pintype "passive")
		)
	)
)
